# BARRELEYE_G2-FPDB_POST-PVT-X02-BOM-X05-20171123_Final.xls.xlsx — DEPOP_GA (bom)
| FOXCONN TECHNOLOGY GROUP |  |  |  |  |  |  |  |  |  |  |  |  |
| BILL OF MATERIAL |  |  |  |  |  |  |  |  |  |  |  |  |
| REV OF  BOM | X05 | CUSTOMER | <name> |  | CUSTOMER P/N |  | PRODUCT CODE |  | PWA  REV | X02 | DATE | 43060 |
| Sourcing (Single/Sole/Multi) | Critical Commodity (Y or N) | Component Class (1, 2, other) | Customer PSL (Y or N) | Item Number | Foxconn P/N | Customer P/N | Part Description | Manufacturer  Full Name | Manufacturer  Part Number | Qty | RoHS Status | Location |
